FILE_TYPE = CONNECTIVITY;
{Allegro Design Entry HDL 16.6-p007 (v16-6-112F) 10/10/2012}
"PAGE_NUMBER" = 198;
0"NC";
1"GND\g";
2"P5V_STBY\g";
3"GND\g";
4"P5V_STBY\g";
5"P5V_STBY\g";
6"P5V\g";
7"P12V\g";
8"P12V_STBY\g";
9"GND\g";
10"GND\g";
11"GND\g";
12"GND\g";
13"GND\g";
14"GND\g";
15"GND\g";
16"GND\g";
17"GND\g";
18"GND\g";
19"P3V3_STBY\g";
20"GND\g";
21"GND\g";
22"P5V_STBY\g";
23"P3V3\g";
24"GND\g";
25"P12V_STBY\g";
26"GND\g";
27"P12V_FAN\g";
28"P3V3_STBY\g";
29"GND\g";
30"P5V_STBY\g";
31"P3V3_SWITCH_G"VOLTAGE"3.3";
32"FM_P3V3_CPLD_EN";
33"TP_SLG55021_P3V3_8";
34"FM_ENABLE_FAN_POWER";
35"TP_SLG55021_P12V_FAN_8";
36"P12V_FAN_SWITCH_G"VOLTAGE"+5V";
37"P5V_SWITCH_G"VOLTAGE"+5V";
38"P12V_SWITCH_G"VOLTAGE"+3.3V";
39"TP_SLG55021_P12V_MAIN_8";
40"FM_P12V_MAIN_SW_EN";
41"TP_SLG55021_P5V_8";
42"FM_CTNR_PS_ON";
%"SLG55021"
"1","(-7000,3825)","0","mstr_vreg","I1";
;
PART_NUMBER"G56246-001"
MATERIAL"IC"
LOCATION"EU2T1"
CDS_LMAN_SYM_OUTLINE"-250,250,250,-250"
CDS_LIB"mstr_vreg"
ROOM"P3V3_PWR_SWITCH"
CDS_LOCATION"EU2T1"
$SEC"1"
CDS_SEC"1"
PACK_TYPE"SM";
"PG"
$PN"8"33;
"G"
$PN"7"31;
"S"
$PN"6"23;
"D"
$PN"5"19;
"SHDN_N \B"
$PN"3"4;
"ON"
$PN"2"32;
"VCC"
$PN"1"4;
"THPAD"
$PN"9"12;
"GND"
$PN"4"12;
%"GND"
"1","(-2775,3425)","0","mstr_symbols","I12";
;
SIZE"1B"
CDS_LIB"mstr_symbols"
VOLTAGE"0.0V"
BODY_TYPE"PLUMBING"
HDL_POWER"GND";
"A\NAC"1;
%"SLG55021"
"1","(-3300,3800)","0","mstr_vreg","I13";
;
CDS_SEC"1"
MATERIAL"IC"
LOCATION"EU8B1"
PART_NUMBER"G56246-001"
CDS_LIB"mstr_vreg"
CDS_LMAN_SYM_OUTLINE"-250,250,250,-250"
ROOM"P5V_PWR_SWITCH"
PACK_TYPE"SM"
CDS_LOCATION"EU8B1"
SEC"1"
SEC_TYPE"SM";
"PG"
$PN"8"41;
"G"
$PN"7"37;
"S"
$PN"6"6;
"D"
$PN"5"5;
"SHDN_N \B"
$PN"3"30;
"ON"
$PN"2"42;
"VCC"
$PN"1"30;
"THPAD"
$PN"9"1;
"GND"
$PN"4"1;
%"P5V_STBY"
"1","(-7375,2525)","0","mstr_symbols","I15";
;
VOLTAGE"5.0V"
SIZE"1B"
CDS_LIB"mstr_symbols"
BODY_TYPE"PLUMBING"
HDL_POWER"P5V_STBY";
"G\NAC"2;
%"GND"
"1","(-6200,1475)","0","mstr_symbols","I18";
;
CDS_LIB"mstr_symbols"
VOLTAGE"0.0V"
SIZE"1B"
BODY_TYPE"PLUMBING"
HDL_POWER"GND";
"A\NAC"3;
%"SLG55021"
"1","(-6725,1850)","0","mstr_vreg","I19";
;
CDS_SEC"1"
MATERIAL"IC"
LOCATION"EU7E1"
PART_NUMBER"G56246-001"
CDS_LMAN_SYM_OUTLINE"-250,250,250,-250"
CDS_LIB"mstr_vreg"
ROOM"P12V_PWR_SWITCH"
CDS_LOCATION"EU7E1"
SEC"1"
SEC_TYPE"SM"
PACK_TYPE"SM";
"PG"
$PN"8"39;
"G"
$PN"7"38;
"S"
$PN"6"7;
"D"
$PN"5"8;
"SHDN_N \B"
$PN"3"2;
"ON"
$PN"2"40;
"VCC"
$PN"1"2;
"THPAD"
$PN"9"3;
"GND"
$PN"4"3;
%"P5V_STBY"
"1","(-7650,4525)","0","mstr_symbols","I2";
;
VOLTAGE"5.0V"
SIZE"1B"
CDS_LIB"mstr_symbols"
BODY_TYPE"PLUMBING"
HDL_POWER"P5V_STBY";
"G\NAC"4;
%"P5V_STBY"
"1","(-1600,4725)","0","mstr_symbols","I20";
;
VOLTAGE"5.0V"
SIZE"1B"
CDS_LIB"mstr_symbols"
BODY_TYPE"PLUMBING"
HDL_POWER"P5V_STBY";
"G\NAC"5;
%"P5V"
"1","(-1100,3600)","0","mstr_symbols","I21";
;
SIZE"1B"
CDS_LIB"mstr_symbols"
VOLTAGE"+5.0V"
BODY_TYPE"PLUMBING"
HDL_POWER"P5V";
"G\NAC"6;
%"P12V"
"1","(-4675,1625)","0","mstr_symbols","I22";
;
SIZE"1B"
CDS_LIB"mstr_symbols"
VOLTAGE"+12.0V"
BODY_TYPE"PLUMBING"
HDL_POWER"P12V";
"G\NAC"7;
%"P12V_STBY"
"1","(-5325,2575)","0","mstr_symbols","I23";
;
VOLTAGE"12.0V"
SIZE"1B"
CDS_LIB"mstr_symbols"
BODY_TYPE"PLUMBING"
HDL_POWER"P12V_STBY";
"G\NAC"8;
%"CAP_A"
"1","(-8000,4200)","0","dev_discrete","I24";
;
PACK_TYPE"0402V"
PART_NUMBER"A36096-030"
MATERIAL"X7R"
VOLTAGE"16V"
TOLERANCE"10%"
VALUE"0.1UF"
LOCATION"C8F17"
CDS_LIB"dev_discrete"
CDS_LOCATION"C8F17"
CDS_SEC"1"
ROOM"P3V3_PWR_SWITCH"
SEC_TYPE"0402V"
SEC"1";
"B"
$PN"2"9;
"A"
$PN"1"4;
%"GND"
"1","(-8000,4000)","0","mstr_symbols","I25";
;
CDS_LIB"mstr_symbols"
VOLTAGE"0.0V"
SIZE"1B"
BODY_TYPE"PLUMBING"
HDL_POWER"GND";
"A\NAC"9;
%"CAP_A"
"1","(-4300,4125)","0","dev_discrete","I26";
;
MATERIAL"X7R"
PART_NUMBER"A36096-030"
TOLERANCE"10%"
VOLTAGE"16V"
PACK_TYPE"0402V"
LOCATION"C8B8"
VALUE"0.1UF"
CDS_LOCATION"C8B8"
CDS_LIB"dev_discrete"
ROOM"P5V_PWR_SWITCH"
CDS_SEC"1"
SEC_TYPE"0402V"
SEC"1";
"B"
$PN"2"10;
"A"
$PN"1"30;
%"GND"
"1","(-4300,3950)","0","mstr_symbols","I27";
;
VOLTAGE"0.0V"
SIZE"1B"
CDS_LIB"mstr_symbols"
BODY_TYPE"PLUMBING"
HDL_POWER"GND";
"A\NAC"10;
%"CAP_A"
"1","(-7725,2175)","0","dev_discrete","I28";
;
CDS_LOCATION"C8E19"
PACK_TYPE"0402V"
TOLERANCE"10%"
VOLTAGE"16V"
MATERIAL"X7R"
PART_NUMBER"A36096-030"
VALUE"0.1UF"
LOCATION"C8E19"
CDS_LIB"dev_discrete"
ROOM"P12V_PWR_SWITCH"
CDS_SEC"1"
SEC_TYPE"0402V"
SEC"1";
"B"
$PN"2"11;
"A"
$PN"1"2;
%"GND"
"1","(-7725,2000)","0","mstr_symbols","I29";
;
CDS_LIB"mstr_symbols"
VOLTAGE"0.0V"
SIZE"1B"
BODY_TYPE"PLUMBING"
HDL_POWER"GND";
"A\NAC"11;
%"GND"
"1","(-6475,3450)","0","mstr_symbols","I3";
;
VOLTAGE"0.0V"
CDS_LIB"mstr_symbols"
SIZE"1B"
BODY_TYPE"PLUMBING"
HDL_POWER"GND";
"A\NAC"12;
%"CAP_A"
"1","(-1050,4400)","0","dev_discrete","I37";
;
MATERIAL"X7R"
VOLTAGE"16V"
PACK_TYPE"0402V"
TOLERANCE"10%"
VALUE"0.1UF"
PART_NUMBER"A36096-030"
LOCATION"C8B5"
CDS_LIB"dev_discrete"
SEC"1"
SEC_TYPE"0402V"
CDS_SEC"1"
BOM_COST"PWR_SWITCH"
CDS_LOCATION"C8B5"
ROOM"P5V_PWR_SWITCH";
"B"
$PN"2"13;
"A"
$PN"1"5;
%"CAP"
"1","(-1375,4400)","0","mstr_discrete","I38";
;
CDS_SEC"1"
VOLTAGE"16V"
TOLERANCE"10%"
VALUE"10UF"
LOCATION"C8B12"
PACK_TYPE"0805"
MATERIAL"X6S"
PART_NUMBER"C95333-007"
ROOM"P5V_PWR_SWITCH"
CDS_LOCATION"C8B12"
CDS_LIB"mstr_discrete"
SEC"1"
SEC_TYPE"0805";
"A"
$PN"1"5;
"B"
$PN"2"13;
%"GND"
"1","(-1200,4075)","0","mstr_symbols","I39";
;
SIZE"1B"
VOLTAGE"0.0V"
CDS_LIB"mstr_symbols"
BODY_TYPE"PLUMBING"
HDL_POWER"GND";
"A\NAC"13;
%"CAP"
"1","(-1100,3250)","0","mstr_discrete","I40";
;
CDS_SEC"1"
MATERIAL"X6S"
VOLTAGE"16V"
PACK_TYPE"0805"
TOLERANCE"10%"
VALUE"10UF"
LOCATION"C8B6"
PART_NUMBER"C95333-007"
CDS_LIB"mstr_discrete"
CDS_LOCATION"C8B6"
ROOM"P5V_PWR_SWITCH"
SEC"1"
SEC_TYPE"0805";
"A"
$PN"1"6;
"B"
$PN"2"14;
%"CAP_A"
"1","(-775,3250)","0","dev_discrete","I41";
;
PACK_TYPE"0402V"
MATERIAL"X7R"
VOLTAGE"16V"
TOLERANCE"10%"
VALUE"0.1UF"
PART_NUMBER"A36096-030"
LOCATION"C8B7"
CDS_LIB"dev_discrete"
ROOM"P5V_PWR_SWITCH"
CDS_LOCATION"C8B7"
CDS_SEC"1"
SEC_TYPE"0402V"
SEC"1"
BOM_COST"PWR_SWITCH";
"B"
$PN"2"14;
"A"
$PN"1"6;
%"GND"
"1","(-925,2900)","0","mstr_symbols","I42";
;
CDS_LIB"mstr_symbols"
VOLTAGE"0.0V"
SIZE"1B"
BODY_TYPE"PLUMBING"
HDL_POWER"GND";
"A\NAC"14;
%"CAP_A"
"1","(-5050,4275)","0","dev_discrete","I43";
;
PACK_TYPE"0402V"
TOLERANCE"10%"
VOLTAGE"16V"
LOCATION"C2T36"
VALUE"0.1UF"
PART_NUMBER"A36096-030"
MATERIAL"X7R"
CDS_LIB"dev_discrete"
ROOM"P3V3_PWR_SWITCH"
CDS_LOCATION"C2T36"
CDS_SEC"1"
SEC_TYPE"0402V"
SEC"1"
BOM_COST"PWR_SWITCH";
"B"
$PN"2"15;
"A"
$PN"1"19;
%"CAP"
"1","(-5375,4275)","0","mstr_discrete","I44";
;
CDS_SEC"1"
PACK_TYPE"0805"
VALUE"10UF"
VOLTAGE"16V"
LOCATION"C2U1"
PART_NUMBER"C95333-007"
MATERIAL"X6S"
TOLERANCE"10%"
CDS_LIB"mstr_discrete"
SEC_TYPE"0805"
SEC"1"
CDS_LOCATION"C2U1"
ROOM"P3V3_PWR_SWITCH";
"A"
$PN"1"19;
"B"
$PN"2"15;
%"GND"
"1","(-5075,3925)","0","mstr_symbols","I45";
;
VOLTAGE"0.0V"
SIZE"1B"
CDS_LIB"mstr_symbols"
BODY_TYPE"PLUMBING"
HDL_POWER"GND";
"A\NAC"15;
%"CAP_A"
"1","(-4675,3200)","0","dev_discrete","I46";
;
PACK_TYPE"0402V"
MATERIAL"X7R"
VOLTAGE"16V"
TOLERANCE"10%"
VALUE"0.1UF"
LOCATION"C2U19"
PART_NUMBER"A36096-030"
CDS_LOCATION"C2U19"
CDS_LIB"dev_discrete"
ROOM"P3V3_PWR_SWITCH"
BOM_COST"PWR_SWITCH"
CDS_SEC"1"
SEC_TYPE"0402V"
SEC"1";
"B"
$PN"2"16;
"A"
$PN"1"23;
%"CAP"
"1","(-5000,3200)","0","mstr_discrete","I47";
;
CDS_SEC"1"
PACK_TYPE"0805"
MATERIAL"X6S"
VOLTAGE"16V"
TOLERANCE"10%"
VALUE"10UF"
LOCATION"C2U2"
PART_NUMBER"C95333-007"
CDS_LIB"mstr_discrete"
CDS_LOCATION"C2U2"
SEC_TYPE"0805"
SEC"1"
ROOM"P3V3_PWR_SWITCH";
"A"
$PN"1"23;
"B"
$PN"2"16;
%"GND"
"1","(-4775,2850)","0","mstr_symbols","I48";
;
SIZE"1B"
VOLTAGE"0.0V"
CDS_LIB"mstr_symbols"
BODY_TYPE"PLUMBING"
HDL_POWER"GND";
"A\NAC"16;
%"CAP_A"
"1","(-4675,1200)","0","dev_discrete","I49";
;
PACK_TYPE"0402V"
MATERIAL"X7R"
VOLTAGE"16V"
TOLERANCE"10%"
VALUE"0.1UF"
PART_NUMBER"A36096-030"
LOCATION"C7E9"
CDS_LIB"dev_discrete"
CDS_LOCATION"C7E9"
CDS_SEC"1"
ROOM"P12V_PWR_SWITCH"
SEC_TYPE"0402V"
SEC"1"
BOM_COST"PWR_SWITCH";
"B"
$PN"2"17;
"A"
$PN"1"7;
%"CAP"
"1","(-5125,1250)","0","mstr_discrete","I50";
;
CDS_SEC"1"
MATERIAL"X6S"
VOLTAGE"16V"
PACK_TYPE"0805"
TOLERANCE"10%"
VALUE"10UF"
LOCATION"C7E8"
PART_NUMBER"C95333-007"
CDS_LIB"mstr_discrete"
SEC_TYPE"0805"
SEC"1"
CDS_LOCATION"C7E8"
ROOM"P12V_PWR_SWITCH";
"A"
$PN"1"7;
"B"
$PN"2"17;
%"GND"
"1","(-5125,925)","0","mstr_symbols","I51";
;
CDS_LIB"mstr_symbols"
VOLTAGE"0.0V"
SIZE"1B"
BODY_TYPE"PLUMBING"
HDL_POWER"GND";
"A\NAC"17;
%"CAP_A"
"1","(-4775,2250)","0","dev_discrete","I52";
;
MATERIAL"X7R"
VOLTAGE"16V"
TOLERANCE"10%"
LOCATION"C7E5"
PACK_TYPE"0402V"
VALUE"0.1UF"
PART_NUMBER"A36096-030"
CDS_LIB"dev_discrete"
ROOM"P12V_PWR_SWITCH"
CDS_LOCATION"C7E5"
CDS_SEC"1"
SEC_TYPE"0402V"
SEC"1"
BOM_COST"PWR_SWITCH";
"B"
$PN"2"18;
"A"
$PN"1"8;
%"CAP"
"1","(-5100,2250)","0","mstr_discrete","I53";
;
CDS_SEC"1"
MATERIAL"X6S"
VOLTAGE"16V"
TOLERANCE"10%"
PACK_TYPE"0805"
VALUE"10UF"
LOCATION"C7E6"
PART_NUMBER"C95333-007"
CDS_LIB"mstr_discrete"
ROOM"P12V_PWR_SWITCH"
CDS_LOCATION"C7E6"
SEC"1"
SEC_TYPE"0805";
"A"
$PN"1"8;
"B"
$PN"2"18;
%"GND"
"1","(-4800,1900)","0","mstr_symbols","I54";
;
VOLTAGE"0.0V"
CDS_LIB"mstr_symbols"
SIZE"1B"
BODY_TYPE"PLUMBING"
HDL_POWER"GND";
"A\NAC"18;
%"P3V3_STBY"
"1","(-5600,4600)","0","mstr_symbols","I6";
;
VOLTAGE"3.3V"
CDS_LIB"mstr_symbols"
SIZE"1B"
BODY_TYPE"PLUMBING"
HDL_POWER"P3V3_STBY";
"G\NAC"19;
%"CAP"
"1","(-1175,1225)","0","mstr_discrete","I61";
;
CDS_SEC"1"
MATERIAL"X6S"
VOLTAGE"16V"
TOLERANCE"10%"
PACK_TYPE"0805"
VALUE"10UF"
PART_NUMBER"C95333-007"
LOCATION"C1B18"
CDS_LIB"mstr_discrete"
ROOM"P12V_FAN_PWR_SWITCH"
CDS_LOCATION"C1B18"
SEC"1"
SEC_TYPE"0805";
"A"
$PN"1"27;
"B"
$PN"2"20;
%"GND"
"1","(-1175,900)","0","mstr_symbols","I63";
;
VOLTAGE"0.0V"
CDS_LIB"mstr_symbols"
SIZE"1B"
BODY_TYPE"PLUMBING"
HDL_POWER"GND";
"A\NAC"20;
%"CAP_A"
"1","(-725,1225)","0","dev_discrete","I64";
;
MATERIAL"X7R"
VOLTAGE"16V"
PACK_TYPE"0402V"
TOLERANCE"10%"
VALUE"0.1UF"
LOCATION"C1B19"
PART_NUMBER"A36096-030"
CDS_LIB"dev_discrete"
CDS_LOCATION"C1B19"
CDS_SEC"1"
SEC"1"
SEC_TYPE"0402V"
ROOM"P12V_FAN_PWR_SWITCH"
BOM_COST"PWR_SWITCH";
"B"
$PN"2"20;
"A"
$PN"1"27;
%"GND"
"1","(-3775,1950)","0","mstr_symbols","I66";
;
CDS_LIB"mstr_symbols"
SIZE"1B"
VOLTAGE"0.0V"
BODY_TYPE"PLUMBING"
HDL_POWER"GND";
"A\NAC"21;
%"CAP_A"
"1","(-3775,2150)","0","dev_discrete","I67";
;
PACK_TYPE"0402V"
PART_NUMBER"A36096-030"
TOLERANCE"10%"
VOLTAGE"16V"
MATERIAL"X7R"
VALUE"0.1UF"
LOCATION"C9M6"
CDS_LOCATION"C9M6"
CDS_LIB"dev_discrete"
CDS_SEC"1"
ROOM"P12V_FAN_PWR_SWITCH"
SEC_TYPE"0402V"
SEC"1";
"B"
$PN"2"21;
"A"
$PN"1"22;
%"P5V_STBY"
"1","(-3425,2500)","0","mstr_symbols","I68";
;
VOLTAGE"5.0V"
CDS_LIB"mstr_symbols"
SIZE"1B"
BODY_TYPE"PLUMBING"
HDL_POWER"P5V_STBY";
"G\NAC"22;
%"SLG55021"
"1","(-2775,1825)","0","mstr_vreg","I69";
;
CDS_SEC"1"
PART_NUMBER"G56246-001"
MATERIAL"IC"
LOCATION"EU9M1"
CDS_LIB"mstr_vreg"
CDS_LMAN_SYM_OUTLINE"-250,250,250,-250"
ROOM"P12V_FAN_PWR_SWITCH"
CDS_LOCATION"EU9M1"
SEC"1"
SEC_TYPE"SM"
PACK_TYPE"SM";
"PG"
$PN"8"35;
"G"
$PN"7"36;
"S"
$PN"6"27;
"D"
$PN"5"25;
"SHDN_N \B"
$PN"3"22;
"ON"
$PN"2"34;
"VCC"
$PN"1"22;
"THPAD"
$PN"9"24;
"GND"
$PN"4"24;
%"P3V3"
"1","(-5125,3675)","0","mstr_symbols","I7";
;
CDS_LIB"mstr_symbols"
SIZE"1B"
VOLTAGE"+3.3V"
BODY_TYPE"PLUMBING"
HDL_POWER"P3V3";
"G\NAC"23;
%"GND"
"1","(-2250,1450)","0","mstr_symbols","I70";
;
CDS_LIB"mstr_symbols"
SIZE"1B"
VOLTAGE"0.0V"
BODY_TYPE"PLUMBING"
HDL_POWER"GND";
"A\NAC"24;
%"P12V_STBY"
"1","(-1375,2550)","0","mstr_symbols","I73";
;
VOLTAGE"12.0V"
CDS_LIB"mstr_symbols"
SIZE"1B"
BODY_TYPE"PLUMBING"
HDL_POWER"P12V_STBY";
"G\NAC"25;
%"CAP"
"1","(-1150,2225)","0","mstr_discrete","I74";
;
CDS_SEC"1"
VOLTAGE"16V"
TOLERANCE"10%"
VALUE"10UF"
PACK_TYPE"0805"
LOCATION"C9M10"
MATERIAL"X6S"
PART_NUMBER"C95333-007"
CDS_LIB"mstr_discrete"
SEC_TYPE"0805"
SEC"1"
CDS_LOCATION"C9M10"
ROOM"P12V_FAN_PWR_SWITCH";
"A"
$PN"1"25;
"B"
$PN"2"26;
%"GND"
"1","(-850,1900)","0","mstr_symbols","I75";
;
VOLTAGE"0.0V"
CDS_LIB"mstr_symbols"
SIZE"1B"
BODY_TYPE"PLUMBING"
HDL_POWER"GND";
"A\NAC"26;
%"CAP_A"
"1","(-825,2225)","0","dev_discrete","I76";
;
PACK_TYPE"0402V"
LOCATION"C9M9"
PART_NUMBER"A36096-030"
MATERIAL"X7R"
TOLERANCE"10%"
VOLTAGE"16V"
VALUE"0.1UF"
CDS_LIB"dev_discrete"
SEC"1"
SEC_TYPE"0402V"
CDS_SEC"1"
CDS_LOCATION"C9M9"
ROOM"P12V_FAN_PWR_SWITCH"
BOM_COST"PWR_SWITCH";
"B"
$PN"2"26;
"A"
$PN"1"25;
%"P12V_FAN"
"1","(-725,1600)","0","mstr_symbols","I77";
;
VOLTAGE"12.0V"
CDS_LIB"mstr_symbols"
BODY_TYPE"PLUMBING"
HDL_POWER"P12V_FAN";
"G\NAC"27;
%"RES"
"2","(-6925,3050)","0","mstr_discrete","I78";
;
CDS_SEC"1"
WATTAGE"1/16W"
MATERIAL"EMPTY"
PART_NUMBER"G21796-072"
TOLERANCE"1%"
LOCATION"R8E12"
VALUE"4.75K"
PACK_TYPE"0402"
CDS_LIB"mstr_discrete"
ROOM"IO_SLOT"
CDS_LOCATION"R8E12"
BOM_COST"IO_SLOT"
SEC"1"
SEC_TYPE"0402";
"A"
$PN"1"28;
"B"
$PN"2"42;
%"P3V3_STBY"
"1","(-6925,3275)","0","mstr_symbols","I79";
;
CDS_LIB"mstr_symbols"
VOLTAGE"3.3V"
SIZE"1B"
BODY_TYPE"PLUMBING"
HDL_POWER"P3V3_STBY";
"G\NAC"28;
%"RES"
"2","(-6850,2625)","0","mstr_discrete","I83";
;
CDS_SEC"1"
MATERIAL"CHIP"
LOCATION"R8B4"
TOLERANCE"1%"
WATTAGE"1/16W"
VALUE"100.0K"
PACK_TYPE"0402"
PART_NUMBER"G21796-010"
CDS_LIB"mstr_discrete"
CDS_LOCATION"R8B4"
ROOM"HOT_SWAP"
SEC_TYPE"0402"
SEC"1";
"A"
$PN"1"42;
"B"
$PN"2"29;
%"GND"
"1","(-6850,2425)","0","mstr_symbols","I84";
;
VOLTAGE"0.0V"
CDS_LIB"mstr_symbols"
SIZE"1B"
BODY_TYPE"PLUMBING"
HDL_POWER"GND";
"A\NAC"29;
%"MOSFET_N"
"3","(-5650,3900)","2","mstr_discrete","I85";
;
CDS_SEC"1"
MATERIAL"NFET"
LOCATION"Q8G1"
VALUE"BSZ019N03LS"
PART_NUMBER"G26762-001"
CDS_LIB"mstr_discrete"
PACK_TYPE"LCC3"
SEC_TYPE"LCC3"
SEC"1"
CDS_LOCATION"Q8G1";
"DRN"
$PN"5"19;
"SRC"
$PN"1"23;
"GATE"
$PN"4"31;
%"MOSFET_N"
"3","(-1375,1850)","2","mstr_discrete","I86";
;
CDS_SEC"1"
MATERIAL"NFET"
LOCATION"Q1B1"
VALUE"BSZ019N03LS"
PART_NUMBER"G26762-001"
CDS_LIB"mstr_discrete"
CDS_LOCATION"Q1B1"
SEC"1"
SEC_TYPE"LCC3"
PACK_TYPE"LCC3";
"DRN"
$PN"5"25;
"SRC"
$PN"1"27;
"GATE"
$PN"4"36;
%"MOSFET_N"
"3","(-1600,3850)","2","mstr_discrete","I87";
;
CDS_SEC"1"
LOCATION"Q8B1"
PART_NUMBER"G26762-001"
MATERIAL"NFET"
VALUE"BSZ019N03LS"
CDS_LIB"mstr_discrete"
PACK_TYPE"LCC3"
CDS_LOCATION"Q8B1"
SEC"1"
SEC_TYPE"LCC3";
"DRN"
$PN"5"5;
"SRC"
$PN"1"6;
"GATE"
$PN"4"37;
%"MOSFET_N"
"3","(-5325,1850)","2","mstr_discrete","I88";
;
CDS_SEC"1"
MATERIAL"NFET"
PART_NUMBER"G26762-001"
LOCATION"Q7E7"
VALUE"BSZ019N03LS"
PACK_TYPE"LCC3"
CDS_LIB"mstr_discrete"
CDS_LOCATION"Q7E7"
SEC"1"
SEC_TYPE"LCC3";
"DRN"
$PN"5"8;
"SRC"
$PN"1"7;
"GATE"
$PN"4"38;
%"P5V_STBY"
"1","(-3950,4350)","0","mstr_symbols","I9";
;
VOLTAGE"5.0V"
CDS_LIB"mstr_symbols"
SIZE"1B"
BODY_TYPE"PLUMBING"
HDL_POWER"P5V_STBY";
"G\NAC"30;
END.
